# S9S_MB_2U (Grand Teton) — schematic netlist excerpt (pin names and nets, part order shuffled) for the footprints in the layout excerpt that follows; sources: Cadence DE-HDL packaged netlist, KiCad conversion of 03242023_DA0F0TMBIJ0_F0T_Motherboard_J_brd_V01_OCP.brd

R4128  Q_RES  4.7K 5% CHIP  pkg 0402LF  page 146 : A = P3V3_AUX ; B = GPU_3V3IO_RSVD0_FFU_ISO
R4677  Q_RES  33.2 1% CHIP  pkg 0402LF  page 260 : A = PWRGD_P3V3_R1 ; B = PWRGD_P3V3

(kicad_pcb
	(version 20260206)
	(generator "pcbnew")
	(generator_version "10.0")
	(general
		(thickness 1.6)
		(legacy_teardrops no)
	)
	(paper "A4")
	(title_block
		(title "03242023_DA0F0TMBIJ0_F0T_Motherboard_J_brd_V01_OCP.brd")
		(comment 1 "Grand Teton / footprints 428-429 of 6105")
	)
	(layers
		(0 "F.Cu" signal "TOP")
		(4 "In1.Cu" signal "GND")
		(6 "In2.Cu" signal "IN1")
		(8 "In3.Cu" signal "GND1")
		(10 "In4.Cu" signal "IN2")
		(12 "In5.Cu" signal "GND2")
		(14 "In6.Cu" signal "IN3")
		(16 "In7.Cu" signal "GND3")
		(18 "In8.Cu" signal "VCC")
		(20 "In9.Cu" signal "VCC1")
		(22 "In10.Cu" signal "GND4")
		(24 "In11.Cu" signal "IN4")
		(26 "In12.Cu" signal "GND5")
		(28 "In13.Cu" signal "IN5")
		(30 "In14.Cu" signal "GND6")
		(32 "In15.Cu" signal "IN6")
		(34 "In16.Cu" signal "GND7")
		(2 "B.Cu" signal "BOTTOM")
		(9 "F.Adhes" user "F.Adhesive")
		(11 "B.Adhes" user "B.Adhesive")
		(13 "F.Paste" user "Package Geometry/Pastemask Top")
		(15 "B.Paste" user "Package Geometry/Pastemask Bottom")
		(5 "F.SilkS" user "Ref Des/Silkscreen Top")
		(7 "B.SilkS" user "Ref Des/Silkscreen Bottom")
		(1 "F.Mask" user "Board Geometry/Soldermask Top")
		(3 "B.Mask" user "Board Geometry/Soldermask Bottom")
		(17 "Dwgs.User" user "User.Drawings")
		(19 "Cmts.User" user "User.Comments")
		(21 "Eco1.User" user "User.Eco1")
		(23 "Eco2.User" user "User.Eco2")
		(25 "Edge.Cuts" user "Board Geometry/Outline")
		(27 "Margin" user)
		(31 "F.CrtYd" user "Package Geometry/Place Bound Top")
		(29 "B.CrtYd" user "Package Geometry/Place Bound Bottom")
		(35 "F.Fab" user "Ref Des/Assembly Top")
		(33 "B.Fab" user "Ref Des/Assembly Bottom")
	)
	(footprint ""
		(layer "F.Cu")
		(at 304.1396 -421.49395 90)
		(property "Reference" "R4128"
			(at 0 0 90)
			(layer "F.SilkS")
			(hide yes)
			(effects
				(font
					(size 1.27 1.27)
				)
			)
		)
		(property "Value" ""
			(at 0 0 90)
			(layer "F.Fab")
			(effects
				(font
					(size 1.27 1.27)
				)
			)
		)
		(duplicate_pad_numbers_are_jumpers no)
		(fp_line
			(start 0.7874 -0.4064)
			(end 0.7874 0.4064)
			(stroke
				(width 0.1524)
				(type default)
			)
			(layer "F.SilkS")
		)
		(fp_line
			(start -0.7874 -0.4064)
			(end 0.7874 -0.4064)
			(stroke
				(width 0.1524)
				(type default)
			)
			(layer "F.SilkS")
		)
		(fp_line
			(start 0.7874 0.4064)
			(end -0.7874 0.4064)
			(stroke
				(width 0.1524)
				(type default)
			)
			(layer "F.SilkS")
		)
		(fp_line
			(start -0.7874 0.4064)
			(end -0.7874 -0.4064)
			(stroke
				(width 0.1524)
				(type default)
			)
			(layer "F.SilkS")
		)
		(fp_line
			(start -0.12065 -0.305054)
			(end -0.12065 -0.2794)
			(stroke
				(width 0.1)
				(type default)
			)
			(layer "F.Fab")
		)
		(fp_line
			(start -0.67945 -0.305054)
			(end -0.12065 -0.305054)
			(stroke
				(width 0.1)
				(type default)
			)
			(layer "F.Fab")
		)
		(fp_line
			(start 0.67945 -0.3048)
			(end 0.67945 0.3048)
			(stroke
				(width 0.1)
				(type default)
			)
			(layer "F.Fab")
		)
		(fp_line
			(start 0.12065 -0.3048)
			(end 0.67945 -0.3048)
			(stroke
				(width 0.1)
				(type default)
			)
			(layer "F.Fab")
		)
		(fp_line
			(start 0.12065 -0.2794)
			(end 0.12065 -0.3048)
			(stroke
				(width 0.1)
				(type default)
			)
			(layer "F.Fab")
		)
		(fp_line
			(start -0.12065 -0.2794)
			(end 0.12065 -0.2794)
			(stroke
				(width 0.1)
				(type default)
			)
			(layer "F.Fab")
		)
		(fp_line
			(start 0.120396 0.2794)
			(end -0.12065 0.2794)
			(stroke
				(width 0.1)
				(type default)
			)
			(layer "F.Fab")
		)
		(fp_line
			(start -0.12065 0.2794)
			(end -0.12065 0.3048)
			(stroke
				(width 0.1)
				(type default)
			)
			(layer "F.Fab")
		)
		(fp_line
			(start 0.67945 0.3048)
			(end 0.120396 0.3048)
			(stroke
				(width 0.1)
				(type default)
			)
			(layer "F.Fab")
		)
		(fp_line
			(start 0.120396 0.3048)
			(end 0.120396 0.2794)
			(stroke
				(width 0.1)
				(type default)
			)
			(layer "F.Fab")
		)
		(fp_line
			(start -0.12065 0.3048)
			(end -0.67945 0.3048)
			(stroke
				(width 0.1)
				(type default)
			)
			(layer "F.Fab")
		)
		(fp_line
			(start -0.67945 0.3048)
			(end -0.67945 -0.305054)
			(stroke
				(width 0.1)
				(type default)
			)
			(layer "F.Fab")
		)
		(pad "1" smd circle
			(at -0.40005 0 90)
			(size 0 0)
			(layers "F.Cu" "F.Mask" "F.Paste")
			(net "P3V3_AUX")
		)
		(pad "2" smd circle
			(at 0.40005 0 90)
			(size 0 0)
			(layers "F.Cu" "F.Mask" "F.Paste")
			(net "GPU_3V3IO_RSVD0_FFU_ISO")
		)
	)
	(footprint ""
		(layer "F.Cu")
		(at 418.6936 -51.87442 90)
		(property "Reference" "R4677"
			(at 0 0 90)
			(layer "F.SilkS")
			(hide yes)
			(effects
				(font
					(size 1.27 1.27)
				)
			)
		)
		(property "Value" ""
			(at 0 0 90)
			(layer "F.Fab")
			(effects
				(font
					(size 1.27 1.27)
				)
			)
		)
		(duplicate_pad_numbers_are_jumpers no)
		(fp_line
			(start 0.7874 -0.4064)
			(end 0.7874 0.4064)
			(stroke
				(width 0.1524)
				(type default)
			)
			(layer "F.SilkS")
		)
		(fp_line
			(start -0.7874 -0.4064)
			(end 0.7874 -0.4064)
			(stroke
				(width 0.1524)
				(type default)
			)
			(layer "F.SilkS")
		)
		(fp_line
			(start 0.7874 0.4064)
			(end -0.7874 0.4064)
			(stroke
				(width 0.1524)
				(type default)
			)
			(layer "F.SilkS")
		)
		(fp_line
			(start -0.7874 0.4064)
			(end -0.7874 -0.4064)
			(stroke
				(width 0.1524)
				(type default)
			)
			(layer "F.SilkS")
		)
		(fp_line
			(start -0.12065 -0.305054)
			(end -0.12065 -0.2794)
			(stroke
				(width 0.1)
				(type default)
			)
			(layer "F.Fab")
		)
		(fp_line
			(start -0.67945 -0.305054)
			(end -0.12065 -0.305054)
			(stroke
				(width 0.1)
				(type default)
			)
			(layer "F.Fab")
		)
		(fp_line
			(start 0.67945 -0.3048)
			(end 0.67945 0.3048)
			(stroke
				(width 0.1)
				(type default)
			)
			(layer "F.Fab")
		)
		(fp_line
			(start 0.12065 -0.3048)
			(end 0.67945 -0.3048)
			(stroke
				(width 0.1)
				(type default)
			)
			(layer "F.Fab")
		)
		(fp_line
			(start 0.12065 -0.2794)
			(end 0.12065 -0.3048)
			(stroke
				(width 0.1)
				(type default)
			)
			(layer "F.Fab")
		)
		(fp_line
			(start -0.12065 -0.2794)
			(end 0.12065 -0.2794)
			(stroke
				(width 0.1)
				(type default)
			)
			(layer "F.Fab")
		)
		(fp_line
			(start 0.120396 0.2794)
			(end -0.12065 0.2794)
			(stroke
				(width 0.1)
				(type default)
			)
			(layer "F.Fab")
		)
		(fp_line
			(start -0.12065 0.2794)
			(end -0.12065 0.3048)
			(stroke
				(width 0.1)
				(type default)
			)
			(layer "F.Fab")
		)
		(fp_line
			(start 0.67945 0.3048)
			(end 0.120396 0.3048)
			(stroke
				(width 0.1)
				(type default)
			)
			(layer "F.Fab")
		)
		(fp_line
			(start 0.120396 0.3048)
			(end 0.120396 0.2794)
			(stroke
				(width 0.1)
				(type default)
			)
			(layer "F.Fab")
		)
		(fp_line
			(start -0.12065 0.3048)
			(end -0.67945 0.3048)
			(stroke
				(width 0.1)
				(type default)
			)
			(layer "F.Fab")
		)
		(fp_line
			(start -0.67945 0.3048)
			(end -0.67945 -0.305054)
			(stroke
				(width 0.1)
				(type default)
			)
			(layer "F.Fab")
		)
		(pad "1" smd circle
			(at -0.40005 0 90)
			(size 0 0)
			(layers "F.Cu" "F.Mask" "F.Paste")
			(net "PWRGD_P3V3_R1")
		)
		(pad "2" smd circle
			(at 0.40005 0 90)
			(size 0 0)
			(layers "F.Cu" "F.Mask" "F.Paste")
			(net "PWRGD_P3V3")
		)
	)
)
